# S9S_MB_2U (Grand Teton) — schematic netlist excerpt (pin names and nets, part order shuffled) for the footprints in the layout excerpt that follows; sources: Cadence DE-HDL packaged netlist, KiCad conversion of 03242023_DA0F0TMBIJ0_F0T_Motherboard_J_brd_V01_OCP.brd

R3205  Q_RES  49.9 1% CHIP  pkg 0402LF  page 160 : A = FB_BMC_ISOLATE_R2 ; B = FB_BMC_ISOLATE1
PC628  Q_CAP  0.1UF 25V 10% X7R  pkg 0402  page 278 : A = PVCCD_HV_CPU0_ISENSE_N ; B = GND

(kicad_pcb
	(version 20260206)
	(generator "pcbnew")
	(generator_version "10.0")
	(general
		(thickness 1.6)
		(legacy_teardrops no)
	)
	(paper "A4")
	(title_block
		(title "03242023_DA0F0TMBIJ0_F0T_Motherboard_J_brd_V01_OCP.brd")
		(comment 1 "Grand Teton / footprints 752-753 of 6105")
	)
	(layers
		(0 "F.Cu" signal "TOP")
		(4 "In1.Cu" signal "GND")
		(6 "In2.Cu" signal "IN1")
		(8 "In3.Cu" signal "GND1")
		(10 "In4.Cu" signal "IN2")
		(12 "In5.Cu" signal "GND2")
		(14 "In6.Cu" signal "IN3")
		(16 "In7.Cu" signal "GND3")
		(18 "In8.Cu" signal "VCC")
		(20 "In9.Cu" signal "VCC1")
		(22 "In10.Cu" signal "GND4")
		(24 "In11.Cu" signal "IN4")
		(26 "In12.Cu" signal "GND5")
		(28 "In13.Cu" signal "IN5")
		(30 "In14.Cu" signal "GND6")
		(32 "In15.Cu" signal "IN6")
		(34 "In16.Cu" signal "GND7")
		(2 "B.Cu" signal "BOTTOM")
		(9 "F.Adhes" user "F.Adhesive")
		(11 "B.Adhes" user "B.Adhesive")
		(13 "F.Paste" user "Package Geometry/Pastemask Top")
		(15 "B.Paste" user "Package Geometry/Pastemask Bottom")
		(5 "F.SilkS" user "Ref Des/Silkscreen Top")
		(7 "B.SilkS" user "Ref Des/Silkscreen Bottom")
		(1 "F.Mask" user "Board Geometry/Soldermask Top")
		(3 "B.Mask" user "Board Geometry/Soldermask Bottom")
		(17 "Dwgs.User" user "User.Drawings")
		(19 "Cmts.User" user "User.Comments")
		(21 "Eco1.User" user "User.Eco1")
		(23 "Eco2.User" user "User.Eco2")
		(25 "Edge.Cuts" user "Board Geometry/Outline")
		(27 "Margin" user)
		(31 "F.CrtYd" user "Package Geometry/Place Bound Top")
		(29 "B.CrtYd" user "Package Geometry/Place Bound Bottom")
		(35 "F.Fab" user "Ref Des/Assembly Top")
		(33 "B.Fab" user "Ref Des/Assembly Bottom")
	)
	(footprint ""
		(layer "F.Cu")
		(at 152.96388 -128.742948 180)
		(property "Reference" "R3205"
			(at 0 0 180)
			(layer "F.SilkS")
			(hide yes)
			(effects
				(font
					(size 1.27 1.27)
				)
			)
		)
		(property "Value" ""
			(at 0 0 180)
			(layer "F.Fab")
			(effects
				(font
					(size 1.27 1.27)
				)
			)
		)
		(duplicate_pad_numbers_are_jumpers no)
		(fp_line
			(start 0.7874 0.4064)
			(end -0.7874 0.4064)
			(stroke
				(width 0.1524)
				(type default)
			)
			(layer "F.SilkS")
		)
		(fp_line
			(start 0.7874 -0.4064)
			(end 0.7874 0.4064)
			(stroke
				(width 0.1524)
				(type default)
			)
			(layer "F.SilkS")
		)
		(fp_line
			(start -0.7874 0.4064)
			(end -0.7874 -0.4064)
			(stroke
				(width 0.1524)
				(type default)
			)
			(layer "F.SilkS")
		)
		(fp_line
			(start -0.7874 -0.4064)
			(end 0.7874 -0.4064)
			(stroke
				(width 0.1524)
				(type default)
			)
			(layer "F.SilkS")
		)
		(fp_line
			(start 0.67945 0.3048)
			(end 0.120396 0.3048)
			(stroke
				(width 0.1)
				(type default)
			)
			(layer "F.Fab")
		)
		(fp_line
			(start 0.67945 -0.3048)
			(end 0.67945 0.3048)
			(stroke
				(width 0.1)
				(type default)
			)
			(layer "F.Fab")
		)
		(fp_line
			(start 0.12065 -0.2794)
			(end 0.12065 -0.3048)
			(stroke
				(width 0.1)
				(type default)
			)
			(layer "F.Fab")
		)
		(fp_line
			(start 0.12065 -0.3048)
			(end 0.67945 -0.3048)
			(stroke
				(width 0.1)
				(type default)
			)
			(layer "F.Fab")
		)
		(fp_line
			(start 0.120396 0.3048)
			(end 0.120396 0.2794)
			(stroke
				(width 0.1)
				(type default)
			)
			(layer "F.Fab")
		)
		(fp_line
			(start 0.120396 0.2794)
			(end -0.12065 0.2794)
			(stroke
				(width 0.1)
				(type default)
			)
			(layer "F.Fab")
		)
		(fp_line
			(start -0.12065 0.3048)
			(end -0.67945 0.3048)
			(stroke
				(width 0.1)
				(type default)
			)
			(layer "F.Fab")
		)
		(fp_line
			(start -0.12065 0.2794)
			(end -0.12065 0.3048)
			(stroke
				(width 0.1)
				(type default)
			)
			(layer "F.Fab")
		)
		(fp_line
			(start -0.12065 -0.2794)
			(end 0.12065 -0.2794)
			(stroke
				(width 0.1)
				(type default)
			)
			(layer "F.Fab")
		)
		(fp_line
			(start -0.12065 -0.305054)
			(end -0.12065 -0.2794)
			(stroke
				(width 0.1)
				(type default)
			)
			(layer "F.Fab")
		)
		(fp_line
			(start -0.67945 0.3048)
			(end -0.67945 -0.305054)
			(stroke
				(width 0.1)
				(type default)
			)
			(layer "F.Fab")
		)
		(fp_line
			(start -0.67945 -0.305054)
			(end -0.12065 -0.305054)
			(stroke
				(width 0.1)
				(type default)
			)
			(layer "F.Fab")
		)
		(pad "1" smd circle
			(at -0.40005 0 180)
			(size 0 0)
			(layers "F.Cu" "F.Mask" "F.Paste")
			(net "FB_BMC_ISOLATE_R2")
		)
		(pad "2" smd circle
			(at 0.40005 0 180)
			(size 0 0)
			(layers "F.Cu" "F.Mask" "F.Paste")
			(net "FB_BMC_ISOLATE1")
		)
	)
	(footprint ""
		(layer "F.Cu")
		(at 428.226474 -121.61266 180)
		(property "Reference" "PC628"
			(at 0 0 180)
			(layer "F.SilkS")
			(hide yes)
			(effects
				(font
					(size 1.27 1.27)
				)
			)
		)
		(property "Value" ""
			(at 0 0 180)
			(layer "F.Fab")
			(effects
				(font
					(size 1.27 1.27)
				)
			)
		)
		(duplicate_pad_numbers_are_jumpers no)
		(fp_line
			(start 0.7874 0.4064)
			(end -0.7874 0.4064)
			(stroke
				(width 0.1524)
				(type default)
			)
			(layer "F.SilkS")
		)
		(fp_line
			(start 0.7874 -0.4064)
			(end 0.7874 0.4064)
			(stroke
				(width 0.1524)
				(type default)
			)
			(layer "F.SilkS")
		)
		(fp_line
			(start -0.7874 0.4064)
			(end -0.7874 -0.4064)
			(stroke
				(width 0.1524)
				(type default)
			)
			(layer "F.SilkS")
		)
		(fp_line
			(start -0.7874 -0.4064)
			(end 0.7874 -0.4064)
			(stroke
				(width 0.1524)
				(type default)
			)
			(layer "F.SilkS")
		)
		(fp_line
			(start 0.67945 0.3048)
			(end 0.120396 0.3048)
			(stroke
				(width 0.1)
				(type default)
			)
			(layer "F.Fab")
		)
		(fp_line
			(start 0.67945 -0.3048)
			(end 0.67945 0.3048)
			(stroke
				(width 0.1)
				(type default)
			)
			(layer "F.Fab")
		)
		(fp_line
			(start 0.12065 -0.2794)
			(end 0.12065 -0.3048)
			(stroke
				(width 0.1)
				(type default)
			)
			(layer "F.Fab")
		)
		(fp_line
			(start 0.12065 -0.3048)
			(end 0.67945 -0.3048)
			(stroke
				(width 0.1)
				(type default)
			)
			(layer "F.Fab")
		)
		(fp_line
			(start 0.120396 0.3048)
			(end 0.120396 0.2794)
			(stroke
				(width 0.1)
				(type default)
			)
			(layer "F.Fab")
		)
		(fp_line
			(start 0.120396 0.2794)
			(end -0.12065 0.2794)
			(stroke
				(width 0.1)
				(type default)
			)
			(layer "F.Fab")
		)
		(fp_line
			(start -0.12065 0.3048)
			(end -0.67945 0.3048)
			(stroke
				(width 0.1)
				(type default)
			)
			(layer "F.Fab")
		)
		(fp_line
			(start -0.12065 0.2794)
			(end -0.12065 0.3048)
			(stroke
				(width 0.1)
				(type default)
			)
			(layer "F.Fab")
		)
		(fp_line
			(start -0.12065 -0.2794)
			(end 0.12065 -0.2794)
			(stroke
				(width 0.1)
				(type default)
			)
			(layer "F.Fab")
		)
		(fp_line
			(start -0.12065 -0.305054)
			(end -0.12065 -0.2794)
			(stroke
				(width 0.1)
				(type default)
			)
			(layer "F.Fab")
		)
		(fp_line
			(start -0.67945 0.3048)
			(end -0.67945 -0.305054)
			(stroke
				(width 0.1)
				(type default)
			)
			(layer "F.Fab")
		)
		(fp_line
			(start -0.67945 -0.305054)
			(end -0.12065 -0.305054)
			(stroke
				(width 0.1)
				(type default)
			)
			(layer "F.Fab")
		)
		(pad "1" smd circle
			(at -0.40005 0 180)
			(size 0 0)
			(layers "F.Cu" "F.Mask" "F.Paste")
			(net "PVCCD_HV_CPU0_ISENSE_N")
		)
		(pad "2" smd circle
			(at 0.40005 0 180)
			(size 0 0)
			(layers "F.Cu" "F.Mask" "F.Paste")
			(net "GND")
		)
	)
)
